(kicad_pcb
	(version 20260206)
	(generator "pcbnew")
	(generator_version "10.0")
	(general
		(thickness 1.6)
		(legacy_teardrops no)
	)
	(paper "A4")
	(title_block
		(title "peb — Lightning_PEB_BRD.brd")
		(comment 1 "Lightning (Wiwynn / Facebook NVMe JBOF) / footprints 1333-1336 of 2563")
	)
	(layers
		(0 "F.Cu" signal "TOP")
		(4 "In1.Cu" signal "L2GND")
		(6 "In2.Cu" signal "L3")
		(8 "In3.Cu" signal "L4VCC")
		(10 "In4.Cu" signal "L5VCC")
		(12 "In5.Cu" signal "L6")
		(14 "In6.Cu" signal "L7GND")
		(2 "B.Cu" signal "BOTTOM")
		(9 "F.Adhes" user "F.Adhesive")
		(11 "B.Adhes" user "B.Adhesive")
		(13 "F.Paste" user "Package Geometry/Pastemask Top")
		(15 "B.Paste" user "Package Geometry/Pastemask Bottom")
		(5 "F.SilkS" user "Ref Des/Silkscreen Top")
		(7 "B.SilkS" user "Ref Des/Silkscreen Bottom")
		(1 "F.Mask" user "Board Geometry/Soldermask Top")
		(3 "B.Mask" user "Board Geometry/Soldermask Bottom")
		(17 "Dwgs.User" user "User.Drawings")
		(19 "Cmts.User" user "User.Comments")
		(21 "Eco1.User" user "User.Eco1")
		(23 "Eco2.User" user "User.Eco2")
		(25 "Edge.Cuts" user "Board Geometry/Outline")
		(27 "Margin" user)
		(31 "F.CrtYd" user "Package Geometry/Place Bound Top")
		(29 "B.CrtYd" user "Package Geometry/Place Bound Bottom")
		(35 "F.Fab" user "Ref Des/Assembly Top")
		(33 "B.Fab" user "Ref Des/Assembly Bottom")
	)
	(footprint ""
		(layer "F.Cu")
		(at 133.864604 -67.223894 180)
		(property "Reference" "SKT4"
			(at 0 0 180)
			(layer "F.SilkS")
			(hide yes)
			(effects
				(font
					(size 1.27 1.27)
				)
			)
		)
		(property "Value" "SKT-SPI8P-9-GP"
			(at 6.989318 7.128764 180)
			(unlocked yes)
			(layer "F.Fab")
			(hide yes)
			(effects
				(font
					(size 1.016 1.016)
					(thickness 0.1524)
				)
			)
		)
		(property "Device Type" "SKT-SOIC8-104117H235"
			(at 6.989318 5.604764 180)
			(unlocked yes)
			(layer "F.Fab")
			(hide yes)
			(effects
				(font
					(size 1.016 1.016)
					(thickness 0.1524)
				)
			)
		)
		(duplicate_pad_numbers_are_jumpers no)
		(fp_line
			(start 5.4483 1.416304)
			(end 4.0513 3.334004)
			(stroke
				(width 0.1524)
				(type default)
			)
			(layer "F.SilkS")
		)
		(fp_line
			(start 5.4483 -1.416304)
			(end 5.4483 1.416304)
			(stroke
				(width 0.1524)
				(type default)
			)
			(layer "F.SilkS")
		)
		(fp_line
			(start 5.4356 0.762)
			(end 4.6736 0)
			(stroke
				(width 0.1524)
				(type default)
			)
			(layer "F.SilkS")
		)
		(fp_line
			(start 4.6736 0)
			(end 5.4356 -0.762)
			(stroke
				(width 0.1524)
				(type default)
			)
			(layer "F.SilkS")
		)
		(fp_line
			(start 4.0513 5.8293)
			(end -4.0513 5.8293)
			(stroke
				(width 0.1524)
				(type default)
			)
			(layer "F.SilkS")
		)
		(fp_line
			(start 4.0513 3.334004)
			(end 4.0513 5.8293)
			(stroke
				(width 0.1524)
				(type default)
			)
			(layer "F.SilkS")
		)
		(fp_line
			(start 4.0513 -3.334004)
			(end 5.4483 -1.416304)
			(stroke
				(width 0.1524)
				(type default)
			)
			(layer "F.SilkS")
		)
		(fp_line
			(start 4.0513 -5.8293)
			(end 4.0513 -3.334004)
			(stroke
				(width 0.1524)
				(type default)
			)
			(layer "F.SilkS")
		)
		(fp_line
			(start 3.8735 -5.6515)
			(end 3.8735 -3.6449)
			(stroke
				(width 0.508)
				(type default)
			)
			(layer "F.SilkS")
		)
		(fp_line
			(start -4.0513 5.8293)
			(end -4.0513 3.334004)
			(stroke
				(width 0.1524)
				(type default)
			)
			(layer "F.SilkS")
		)
		(fp_line
			(start -4.0513 3.334004)
			(end -5.4483 1.416304)
			(stroke
				(width 0.1524)
				(type default)
			)
			(layer "F.SilkS")
		)
		(fp_line
			(start -4.0513 -3.334004)
			(end -4.0513 -5.8293)
			(stroke
				(width 0.1524)
				(type default)
			)
			(layer "F.SilkS")
		)
		(fp_line
			(start -4.0513 -5.8293)
			(end 4.0513 -5.8293)
			(stroke
				(width 0.1524)
				(type default)
			)
			(layer "F.SilkS")
		)
		(fp_line
			(start -5.4483 1.416304)
			(end -5.4483 -1.416304)
			(stroke
				(width 0.1524)
				(type default)
			)
			(layer "F.SilkS")
		)
		(fp_line
			(start -5.4483 -1.416304)
			(end -4.0513 -3.334004)
			(stroke
				(width 0.1524)
				(type default)
			)
			(layer "F.SilkS")
		)
		(fp_poly
			(pts
				(xy -2.159 3.047492) (xy 2.159 3.047492) (xy 2.159 -3.047492) (xy -2.159 -3.047492)
			)
			(stroke
				(width 0)
				(type default)
			)
			(fill yes)
			(layer "F.SilkS")
		)
		(fp_rect
			(start -5.7023 9.7282)
			(end 5.7023 5.8293)
			(stroke
				(width 0)
				(type default)
			)
			(fill no)
			(layer "F.CrtYd")
		)
		(fp_rect
			(start -5.7023 -5.8293)
			(end 5.7023 -10.5156)
			(stroke
				(width 0)
				(type default)
			)
			(fill no)
			(layer "F.CrtYd")
		)
		(fp_poly
			(pts
				(xy 3.7973 5.8293) (xy 3.7973 3.2512) (xy 5.1943 1.3335) (xy 5.1943 -1.3335) (xy 3.7973 -3.2512)
				(xy 3.7973 -5.8293) (xy 5.7023 -5.8293) (xy 5.7023 5.8293)
			)
			(stroke
				(width 0)
				(type default)
			)
			(fill no)
			(layer "F.CrtYd")
		)
		(fp_poly
			(pts
				(xy -5.7023 5.8293) (xy -5.7023 -5.8293) (xy -3.7973 -5.8293) (xy -3.7973 -3.2512) (xy -5.1943 -1.3335)
				(xy -5.1943 1.3335) (xy -3.7973 3.2512) (xy -3.7973 5.8293)
			)
			(stroke
				(width 0)
				(type default)
			)
			(fill no)
			(layer "F.CrtYd")
		)
		(fp_poly
			(pts
				(xy -3.7973 5.8293) (xy -3.7973 3.2512) (xy -5.1943 1.3335) (xy -5.1943 -1.3335) (xy -3.7973 -3.2512)
				(xy -3.7973 -5.8293) (xy 3.7973 -5.8293) (xy 3.7973 -3.2512) (xy 5.1943 -1.3335) (xy 5.1943 1.3335)
				(xy 3.7973 3.2512) (xy 3.7973 5.8293)
			)
			(stroke
				(width 0)
				(type default)
			)
			(fill no)
			(layer "F.CrtYd")
		)
		(fp_rect
			(start -5.7023 9.7282)
			(end 5.7023 -10.5156)
			(stroke
				(width 0)
				(type default)
			)
			(fill no)
			(layer "F.Fab")
		)
		(pad "1" smd rect
			(at 1.905 -3.999992 180)
			(size 0.508 1.4986)
			(layers "F.Cu" "F.Mask" "F.Paste")
			(net "SPI_CSB0_0")
		)
		(pad "2" smd rect
			(at 0.635 -3.999992 180)
			(size 0.508 1.4986)
			(layers "F.Cu" "F.Mask" "F.Paste")
			(net "SPI_DATA0_1_R")
		)
		(pad "3" smd rect
			(at -0.635 -3.999992 180)
			(size 0.508 1.4986)
			(layers "F.Cu" "F.Mask" "F.Paste")
			(net "SPI_DATA0_2_R")
		)
		(pad "4" smd rect
			(at -1.905 -3.999992 180)
			(size 0.508 1.4986)
			(layers "F.Cu" "F.Mask" "F.Paste")
			(net "GND")
		)
		(pad "5" smd rect
			(at -1.905 3.999992 180)
			(size 0.508 1.4986)
			(layers "F.Cu" "F.Mask" "F.Paste")
			(net "SPI_DATA0_0_R")
		)
		(pad "6" smd rect
			(at -0.635 3.999992 180)
			(size 0.508 1.4986)
			(layers "F.Cu" "F.Mask" "F.Paste")
			(net "SPI_CLK0_R")
		)
		(pad "7" smd rect
			(at 0.635 3.999992 180)
			(size 0.508 1.4986)
			(layers "F.Cu" "F.Mask" "F.Paste")
			(net "SPI_DATA0_3_R")
		)
		(pad "8" smd rect
			(at 1.905 3.999992 180)
			(size 0.508 1.4986)
			(layers "F.Cu" "F.Mask" "F.Paste")
			(net "P1V8_STBY")
		)
		(zone
			(layer "F.Cu")
			(hatch none 0.5)
			(connect_pads
				(clearance 0)
			)
			(min_thickness 0.25)
			(keepout
				(tracks allowed)
				(vias not_allowed)
				(pads allowed)
				(copperpour not_allowed)
				(footprints allowed)
			)
			(placement
				(enabled no)
				(sheetname "")
			)
			(fill
				(thermal_gap 0.5)
				(thermal_bridge_width 0.5)
				(island_removal_mode 0)
			)
			(polygon
				(pts
					(xy 136.023604 -70.474586) (xy 131.705604 -70.474586) (xy 131.705604 -69.966586) (xy 136.023604 -69.966586)
				)
			)
		)
		(zone
			(layer "F.Cu")
			(hatch none 0.5)
			(connect_pads
				(clearance 0)
			)
			(min_thickness 0.25)
			(keepout
				(tracks allowed)
				(vias not_allowed)
				(pads allowed)
				(copperpour not_allowed)
				(footprints allowed)
			)
			(placement
				(enabled no)
				(sheetname "")
			)
			(fill
				(thermal_gap 0.5)
				(thermal_bridge_width 0.5)
				(island_removal_mode 0)
			)
			(polygon
				(pts
					(xy 136.023604 -70.474586) (xy 131.705604 -70.474586) (xy 131.705604 -63.973202) (xy 136.023604 -63.973202)
				)
			)
		)
		(zone
			(layer "F.Cu")
			(hatch none 0.5)
			(connect_pads
				(clearance 0)
			)
			(min_thickness 0.25)
			(keepout
				(tracks not_allowed)
				(vias allowed)
				(pads allowed)
				(copperpour not_allowed)
				(footprints allowed)
			)
			(placement
				(enabled no)
				(sheetname "")
			)
			(fill
				(thermal_gap 0.5)
				(thermal_bridge_width 0.5)
				(island_removal_mode 0)
			)
			(polygon
				(pts
					(xy 136.023604 -70.474586) (xy 131.705604 -70.474586) (xy 131.705604 -63.973202) (xy 136.023604 -63.973202)
				)
			)
		)
		(zone
			(layer "F.Cu")
			(hatch none 0.5)
			(connect_pads
				(clearance 0)
			)
			(min_thickness 0.25)
			(keepout
				(tracks allowed)
				(vias not_allowed)
				(pads allowed)
				(copperpour not_allowed)
				(footprints allowed)
			)
			(placement
				(enabled no)
				(sheetname "")
			)
			(fill
				(thermal_gap 0.5)
				(thermal_bridge_width 0.5)
				(island_removal_mode 0)
			)
			(polygon
				(pts
					(xy 136.023604 -64.481202) (xy 131.705604 -64.481202) (xy 131.705604 -63.973202) (xy 136.023604 -63.973202)
				)
			)
		)
	)
	(footprint ""
		(layer "F.Cu")
		(at 324.612 -97.917)
		(property "Reference" "TP301"
			(at 0 0 0)
			(layer "F.SilkS")
			(hide yes)
			(effects
				(font
					(size 1.27 1.27)
				)
			)
		)
		(property "Value" "TPAD28-2-GP"
			(at -0.0127 -1.6637 0)
			(unlocked yes)
			(layer "F.Fab")
			(hide yes)
			(effects
				(font
					(size 1.016 1.016)
					(thickness 0.1524)
				)
			)
		)
		(property "Device Type" "TPAD28"
			(at -0.0127 -3.1877 0)
			(unlocked yes)
			(layer "F.Fab")
			(hide yes)
			(effects
				(font
					(size 1.016 1.016)
					(thickness 0.1524)
				)
			)
		)
		(duplicate_pad_numbers_are_jumpers no)
		(fp_poly
			(pts
				(arc
					(start 0.3556 0)
					(mid -0.3556 0)
					(end 0.3556 0)
				)
			)
			(stroke
				(width 0)
				(type default)
			)
			(fill no)
			(layer "F.CrtYd")
		)
		(fp_poly
			(pts
				(arc
					(start 0.6096 0)
					(mid -0.6096 0)
					(end 0.6096 0)
				)
			)
			(stroke
				(width 0)
				(type default)
			)
			(fill no)
			(layer "F.Fab")
		)
		(pad "1" smd circle
			(at 0 0)
			(size 0.7112 0.7112)
			(layers "F.Cu" "F.Mask" "F.Paste")
			(net "MAX7311_TP301")
		)
	)
	(footprint ""
		(layer "F.Cu")
		(at 29.52369 -114.18189 180)
		(property "Reference" "R605"
			(at 0 0 180)
			(layer "F.SilkS")
			(hide yes)
			(effects
				(font
					(size 1.27 1.27)
				)
			)
		)
		(property "Value" "10KR2F-2-GP"
			(at 0.064008 -3.993896 180)
			(unlocked yes)
			(layer "F.Fab")
			(hide yes)
			(effects
				(font
					(size 1.016 1.016)
					(thickness 0.1524)
				)
			)
		)
		(property "Device Type" "R402H16"
			(at 0.064008 -5.517896 180)
			(unlocked yes)
			(layer "F.Fab")
			(hide yes)
			(effects
				(font
					(size 1.016 1.016)
					(thickness 0.1524)
				)
			)
		)
		(duplicate_pad_numbers_are_jumpers no)
		(fp_line
			(start 0.508 -0.9398)
			(end -0.508 -0.9398)
			(stroke
				(width 0.1524)
				(type default)
			)
			(layer "F.SilkS")
		)
		(fp_line
			(start -0.508 -0.9398)
			(end -0.508 0.9398)
			(stroke
				(width 0.1524)
				(type default)
			)
			(layer "F.SilkS")
		)
		(fp_rect
			(start -0.508 0.9398)
			(end 0.508 -0.9398)
			(stroke
				(width 0)
				(type default)
			)
			(fill no)
			(layer "F.CrtYd")
		)
		(fp_rect
			(start -0.508 0.9398)
			(end 0.508 -0.9398)
			(stroke
				(width 0)
				(type default)
			)
			(fill no)
			(layer "F.Fab")
		)
		(pad "1" smd custom
			(at 0 -0.4445 180)
			(size 0.1397 0.1397)
			(layers "F.Cu" "F.Mask" "F.Paste")
			(net "P3V3_STBY")
			(options
				(clearance outline)
				(anchor circle)
			)
			(primitives
				(gr_poly
					(pts
						(arc
							(start -0.1778 -0.2794)
							(mid -0.249642 -0.249642)
							(end -0.2794 -0.1778)
						)
						(arc
							(start -0.2794 0.1778)
							(mid -0.249642 0.249642)
							(end -0.1778 0.2794)
						)
						(arc
							(start 0.1778 0.2794)
							(mid 0.249642 0.249642)
							(end 0.2794 0.1778)
						)
						(arc
							(start 0.2794 -0.1778)
							(mid 0.249642 -0.249642)
							(end 0.1778 -0.2794)
						)
					)
					(width 0)
					(fill yes)
				)
			)
		)
		(pad "2" smd custom
			(at 0 0.4445 180)
			(size 0.1397 0.1397)
			(layers "F.Cu" "F.Mask" "F.Paste")
			(net "I2C_MUX_RESET_PEB")
			(options
				(clearance outline)
				(anchor circle)
			)
			(primitives
				(gr_poly
					(pts
						(arc
							(start -0.1778 -0.2794)
							(mid -0.249642 -0.249642)
							(end -0.2794 -0.1778)
						)
						(arc
							(start -0.2794 0.1778)
							(mid -0.249642 0.249642)
							(end -0.1778 0.2794)
						)
						(arc
							(start 0.1778 0.2794)
							(mid 0.249642 0.249642)
							(end 0.2794 0.1778)
						)
						(arc
							(start 0.2794 -0.1778)
							(mid 0.249642 -0.249642)
							(end 0.1778 -0.2794)
						)
					)
					(width 0)
					(fill yes)
				)
			)
		)
	)
	(footprint ""
		(layer "F.Cu")
		(at 64.447674 -67.12712)
		(property "Reference" "SKT3"
			(at 0 0 0)
			(layer "F.SilkS")
			(hide yes)
			(effects
				(font
					(size 1.27 1.27)
				)
			)
		)
		(property "Value" "SKT-SPI16P-GP-U"
			(at -8.9916 4.641596 0)
			(unlocked yes)
			(layer "F.Fab")
			(hide yes)
			(effects
				(font
					(size 1.016 1.016)
					(thickness 0.1524)
				)
			)
		)
		(property "Device Type" "SKT-SOIC16-153139H258"
			(at -8.9916 3.117596 0)
			(unlocked yes)
			(layer "F.Fab")
			(hide yes)
			(effects
				(font
					(size 1.016 1.016)
					(thickness 0.1524)
				)
			)
		)
		(duplicate_pad_numbers_are_jumpers no)
		(fp_line
			(start -7.8994 -6.4008)
			(end -7.8994 6.4008)
			(stroke
				(width 0.1524)
				(type default)
			)
			(layer "F.SilkS")
		)
		(fp_line
			(start -7.8994 6.4008)
			(end 7.8994 6.4008)
			(stroke
				(width 0.1524)
				(type default)
			)
			(layer "F.SilkS")
		)
		(fp_line
			(start 6.7183 0.0762)
			(end 7.8994 1.2573)
			(stroke
				(width 0.1524)
				(type default)
			)
			(layer "F.SilkS")
		)
		(fp_line
			(start 7.7216 -6.223)
			(end 7.7216 -3.6576)
			(stroke
				(width 0.508)
				(type default)
			)
			(layer "F.SilkS")
		)
		(fp_line
			(start 7.8867 -1.0922)
			(end 6.7183 0.0762)
			(stroke
				(width 0.1524)
				(type default)
			)
			(layer "F.SilkS")
		)
		(fp_line
			(start 7.8994 -6.4008)
			(end -7.8994 -6.4008)
			(stroke
				(width 0.1524)
				(type default)
			)
			(layer "F.SilkS")
		)
		(fp_line
			(start 7.8994 6.4008)
			(end 7.8994 -6.4008)
			(stroke
				(width 0.1524)
				(type default)
			)
			(layer "F.SilkS")
		)
		(fp_poly
			(pts
				(xy -4.699 -3.855466) (xy -4.699 3.855466) (xy 4.699 3.855466) (xy 4.699 -3.855466)
			)
			(stroke
				(width 0)
				(type default)
			)
			(fill yes)
			(layer "F.SilkS")
		)
		(fp_rect
			(start -8.1534 -6.4008)
			(end 8.1534 -12.5222)
			(stroke
				(width 0)
				(type default)
			)
			(fill no)
			(layer "F.CrtYd")
		)
		(fp_rect
			(start -8.1534 11.6078)
			(end 8.1534 6.4008)
			(stroke
				(width 0)
				(type default)
			)
			(fill no)
			(layer "F.CrtYd")
		)
		(fp_poly
			(pts
				(xy -8.1534 6.4008) (xy -8.1534 -6.4008) (xy -6.2484 -6.4008) (xy -6.2484 -2.6416) (xy -7.6454 -2.6416)
				(xy -7.6454 2.6416) (xy -6.2484 2.6416) (xy -6.2484 6.4008)
			)
			(stroke
				(width 0)
				(type default)
			)
			(fill no)
			(layer "F.CrtYd")
		)
		(fp_poly
			(pts
				(xy 6.2484 -6.4008) (xy 8.1534 -6.4008) (xy 8.1534 6.4008) (xy 6.2484 6.4008) (xy 6.2484 2.6416)
				(xy 7.6454 2.6416) (xy 7.6454 -2.6416) (xy 6.2484 -2.6416)
			)
			(stroke
				(width 0)
				(type default)
			)
			(fill no)
			(layer "F.CrtYd")
		)
		(fp_poly
			(pts
				(xy 6.2484 -6.4008) (xy -6.2484 -6.4008) (xy -6.2484 -2.6416) (xy -7.6454 -2.6416) (xy -7.6454 2.6416)
				(xy -6.2484 2.6416) (xy -6.2484 6.4008) (xy 6.2484 6.4008) (xy 6.2484 2.6416) (xy 7.6454 2.6416)
				(xy 7.6454 -2.6416) (xy 6.2484 -2.6416)
			)
			(stroke
				(width 0)
				(type default)
			)
			(fill no)
			(layer "F.CrtYd")
		)
		(fp_rect
			(start -8.1534 11.6078)
			(end 8.1534 -12.5222)
			(stroke
				(width 0)
				(type default)
			)
			(fill no)
			(layer "F.Fab")
		)
		(pad "1" smd rect
			(at 4.445 -4.896866)
			(size 0.508 1.6764)
			(layers "F.Cu" "F.Mask" "F.Paste")
			(net "PU_IBMC_BT_HOLD_N")
		)
		(pad "2" smd rect
			(at 3.175 -4.896866)
			(size 0.508 1.6764)
			(layers "F.Cu" "F.Mask" "F.Paste")
			(net "P3V3_STBY")
		)
		(pad "3" smd rect
			(at 1.905 -4.896866)
			(size 0.508 1.6764)
			(layers "F.Cu" "F.Mask" "F.Paste")
			(net "U19_PERST_N")
		)
		(pad "4" smd rect
			(at 0.635 -4.896866)
			(size 0.508 1.6764)
			(layers "F.Cu" "F.Mask" "F.Paste")
			(net "Net_2114")
		)
		(pad "5" smd rect
			(at -0.635 -4.896866)
			(size 0.508 1.6764)
			(layers "F.Cu" "F.Mask" "F.Paste")
			(net "Net_2113")
		)
		(pad "6" smd rect
			(at -1.905 -4.896866)
			(size 0.508 1.6764)
			(layers "F.Cu" "F.Mask" "F.Paste")
			(net "Net_2112")
		)
		(pad "7" smd rect
			(at -3.175 -4.896866)
			(size 0.508 1.6764)
			(layers "F.Cu" "F.Mask" "F.Paste")
			(net "FLA_CS1_R")
		)
		(pad "8" smd rect
			(at -4.445 -4.896866)
			(size 0.508 1.6764)
			(layers "F.Cu" "F.Mask" "F.Paste")
			(net "ROMD2_R")
		)
		(pad "9" smd rect
			(at -4.445 4.896866)
			(size 0.508 1.6764)
			(layers "F.Cu" "F.Mask" "F.Paste")
			(net "FLA_WPN")
		)
		(pad "10" smd rect
			(at -3.175 4.896866)
			(size 0.508 1.6764)
			(layers "F.Cu" "F.Mask" "F.Paste")
			(net "GND")
		)
		(pad "11" smd rect
			(at -1.905 4.896866)
			(size 0.508 1.6764)
			(layers "F.Cu" "F.Mask" "F.Paste")
			(net "Net_2118")
		)
		(pad "12" smd rect
			(at -0.635 4.896866)
			(size 0.508 1.6764)
			(layers "F.Cu" "F.Mask" "F.Paste")
			(net "Net_2117")
		)
		(pad "13" smd rect
			(at 0.635 4.896866)
			(size 0.508 1.6764)
			(layers "F.Cu" "F.Mask" "F.Paste")
			(net "Net_2116")
		)
		(pad "14" smd rect
			(at 1.905 4.896866)
			(size 0.508 1.6764)
			(layers "F.Cu" "F.Mask" "F.Paste")
			(net "Net_2115")
		)
		(pad "15" smd rect
			(at 3.175 4.896866)
			(size 0.508 1.6764)
			(layers "F.Cu" "F.Mask" "F.Paste")
			(net "ROMD1_R")
		)
		(pad "16" smd rect
			(at 4.445 4.896866)
			(size 0.508 1.6764)
			(layers "F.Cu" "F.Mask" "F.Paste")
			(net "ROMD0_R")
		)
	)
)
